# SCM (Grand Teton) — schematic netlist excerpt (pin names and nets, part order shuffled) for the footprints in the layout excerpt that follows; sources: Cadence DE-HDL packaged netlist, KiCad conversion of 12092022_DA0F0TMDCD0_F0T_Management_Board_D_brd_V3_OCP.brd

C178  Q_CAP  470PF 50V 10% X7R  pkg 0402  page 29 : A = P5V_USB_REAR ; B = GND
R328  Q_RES  120 1% CHIP  pkg 0402LF  page 20 : A = GND ; B = M_BMC_DDR4_MA<2>

(kicad_pcb
	(version 20260206)
	(generator "pcbnew")
	(generator_version "10.0")
	(general
		(thickness 1.6)
		(legacy_teardrops no)
	)
	(paper "A4")
	(title_block
		(title "12092022_DA0F0TMDCD0_F0T_Management_Board_D_brd_V3_OCP.brd")
		(comment 1 "Grand Teton / footprints 320-321 of 1440")
	)
	(layers
		(0 "F.Cu" signal "TOP")
		(4 "In1.Cu" signal "GND")
		(6 "In2.Cu" signal "IN1")
		(8 "In3.Cu" signal "GND1")
		(10 "In4.Cu" signal "IN2")
		(12 "In5.Cu" signal "VCC")
		(14 "In6.Cu" signal "VCC1")
		(16 "In7.Cu" signal "IN3")
		(18 "In8.Cu" signal "GND2")
		(20 "In9.Cu" signal "IN4")
		(22 "In10.Cu" signal "GND3")
		(2 "B.Cu" signal "BOTTOM")
		(9 "F.Adhes" user "F.Adhesive")
		(11 "B.Adhes" user "B.Adhesive")
		(13 "F.Paste" user "Package Geometry/Pastemask Top")
		(15 "B.Paste" user "Package Geometry/Pastemask Bottom")
		(5 "F.SilkS" user "Ref Des/Silkscreen Top")
		(7 "B.SilkS" user "Ref Des/Silkscreen Bottom")
		(1 "F.Mask" user "Board Geometry/Soldermask Top")
		(3 "B.Mask" user "Board Geometry/Soldermask Bottom")
		(17 "Dwgs.User" user "User.Drawings")
		(19 "Cmts.User" user "User.Comments")
		(21 "Eco1.User" user "User.Eco1")
		(23 "Eco2.User" user "User.Eco2")
		(25 "Edge.Cuts" user "Board Geometry/Outline")
		(27 "Margin" user)
		(31 "F.CrtYd" user "Package Geometry/Place Bound Top")
		(29 "B.CrtYd" user "Package Geometry/Place Bound Bottom")
		(35 "F.Fab" user "Ref Des/Assembly Top")
		(33 "B.Fab" user "Ref Des/Assembly Bottom")
	)
	(footprint ""
		(layer "F.Cu")
		(at 76.691744 -35.502088 90)
		(property "Reference" "R328"
			(at 0 0 90)
			(layer "F.SilkS")
			(hide yes)
			(effects
				(font
					(size 1.27 1.27)
				)
			)
		)
		(property "Value" ""
			(at 0 0 90)
			(layer "F.Fab")
			(effects
				(font
					(size 1.27 1.27)
				)
			)
		)
		(duplicate_pad_numbers_are_jumpers no)
		(fp_line
			(start 0.7874 -0.4064)
			(end 0.7874 0.4064)
			(stroke
				(width 0.1524)
				(type default)
			)
			(layer "F.SilkS")
		)
		(fp_line
			(start -0.7874 -0.4064)
			(end 0.7874 -0.4064)
			(stroke
				(width 0.1524)
				(type default)
			)
			(layer "F.SilkS")
		)
		(fp_line
			(start 0.7874 0.4064)
			(end -0.7874 0.4064)
			(stroke
				(width 0.1524)
				(type default)
			)
			(layer "F.SilkS")
		)
		(fp_line
			(start -0.7874 0.4064)
			(end -0.7874 -0.4064)
			(stroke
				(width 0.1524)
				(type default)
			)
			(layer "F.SilkS")
		)
		(fp_line
			(start -0.12065 -0.305054)
			(end -0.12065 -0.2794)
			(stroke
				(width 0.1)
				(type default)
			)
			(layer "F.Fab")
		)
		(fp_line
			(start -0.67945 -0.305054)
			(end -0.12065 -0.305054)
			(stroke
				(width 0.1)
				(type default)
			)
			(layer "F.Fab")
		)
		(fp_line
			(start 0.67945 -0.3048)
			(end 0.67945 0.3048)
			(stroke
				(width 0.1)
				(type default)
			)
			(layer "F.Fab")
		)
		(fp_line
			(start 0.12065 -0.3048)
			(end 0.67945 -0.3048)
			(stroke
				(width 0.1)
				(type default)
			)
			(layer "F.Fab")
		)
		(fp_line
			(start 0.12065 -0.2794)
			(end 0.12065 -0.3048)
			(stroke
				(width 0.1)
				(type default)
			)
			(layer "F.Fab")
		)
		(fp_line
			(start -0.12065 -0.2794)
			(end 0.12065 -0.2794)
			(stroke
				(width 0.1)
				(type default)
			)
			(layer "F.Fab")
		)
		(fp_line
			(start 0.120396 0.2794)
			(end -0.12065 0.2794)
			(stroke
				(width 0.1)
				(type default)
			)
			(layer "F.Fab")
		)
		(fp_line
			(start -0.12065 0.2794)
			(end -0.12065 0.3048)
			(stroke
				(width 0.1)
				(type default)
			)
			(layer "F.Fab")
		)
		(fp_line
			(start 0.67945 0.3048)
			(end 0.120396 0.3048)
			(stroke
				(width 0.1)
				(type default)
			)
			(layer "F.Fab")
		)
		(fp_line
			(start 0.120396 0.3048)
			(end 0.120396 0.2794)
			(stroke
				(width 0.1)
				(type default)
			)
			(layer "F.Fab")
		)
		(fp_line
			(start -0.12065 0.3048)
			(end -0.67945 0.3048)
			(stroke
				(width 0.1)
				(type default)
			)
			(layer "F.Fab")
		)
		(fp_line
			(start -0.67945 0.3048)
			(end -0.67945 -0.305054)
			(stroke
				(width 0.1)
				(type default)
			)
			(layer "F.Fab")
		)
		(pad "1" smd circle
			(at -0.40005 0 90)
			(size 0 0)
			(layers "F.Cu" "F.Mask" "F.Paste")
			(net "GND")
		)
		(pad "2" smd circle
			(at 0.40005 0 90)
			(size 0 0)
			(layers "F.Cu" "F.Mask" "F.Paste")
			(net "M_BMC_DDR4_MA<2>")
		)
	)
	(footprint ""
		(layer "F.Cu")
		(at 48.593248 -20.435062 90)
		(property "Reference" "C178"
			(at 0 0 90)
			(layer "F.SilkS")
			(hide yes)
			(effects
				(font
					(size 1.27 1.27)
				)
			)
		)
		(property "Value" ""
			(at 0 0 90)
			(layer "F.Fab")
			(effects
				(font
					(size 1.27 1.27)
				)
			)
		)
		(duplicate_pad_numbers_are_jumpers no)
		(fp_line
			(start 0.7874 -0.4064)
			(end 0.7874 0.4064)
			(stroke
				(width 0.1524)
				(type default)
			)
			(layer "F.SilkS")
		)
		(fp_line
			(start -0.7874 -0.4064)
			(end 0.7874 -0.4064)
			(stroke
				(width 0.1524)
				(type default)
			)
			(layer "F.SilkS")
		)
		(fp_line
			(start 0.7874 0.4064)
			(end -0.7874 0.4064)
			(stroke
				(width 0.1524)
				(type default)
			)
			(layer "F.SilkS")
		)
		(fp_line
			(start -0.7874 0.4064)
			(end -0.7874 -0.4064)
			(stroke
				(width 0.1524)
				(type default)
			)
			(layer "F.SilkS")
		)
		(fp_line
			(start -0.12065 -0.305054)
			(end -0.12065 -0.2794)
			(stroke
				(width 0.1)
				(type default)
			)
			(layer "F.Fab")
		)
		(fp_line
			(start -0.67945 -0.305054)
			(end -0.12065 -0.305054)
			(stroke
				(width 0.1)
				(type default)
			)
			(layer "F.Fab")
		)
		(fp_line
			(start 0.67945 -0.3048)
			(end 0.67945 0.3048)
			(stroke
				(width 0.1)
				(type default)
			)
			(layer "F.Fab")
		)
		(fp_line
			(start 0.12065 -0.3048)
			(end 0.67945 -0.3048)
			(stroke
				(width 0.1)
				(type default)
			)
			(layer "F.Fab")
		)
		(fp_line
			(start 0.12065 -0.2794)
			(end 0.12065 -0.3048)
			(stroke
				(width 0.1)
				(type default)
			)
			(layer "F.Fab")
		)
		(fp_line
			(start -0.12065 -0.2794)
			(end 0.12065 -0.2794)
			(stroke
				(width 0.1)
				(type default)
			)
			(layer "F.Fab")
		)
		(fp_line
			(start 0.120396 0.2794)
			(end -0.12065 0.2794)
			(stroke
				(width 0.1)
				(type default)
			)
			(layer "F.Fab")
		)
		(fp_line
			(start -0.12065 0.2794)
			(end -0.12065 0.3048)
			(stroke
				(width 0.1)
				(type default)
			)
			(layer "F.Fab")
		)
		(fp_line
			(start 0.67945 0.3048)
			(end 0.120396 0.3048)
			(stroke
				(width 0.1)
				(type default)
			)
			(layer "F.Fab")
		)
		(fp_line
			(start 0.120396 0.3048)
			(end 0.120396 0.2794)
			(stroke
				(width 0.1)
				(type default)
			)
			(layer "F.Fab")
		)
		(fp_line
			(start -0.12065 0.3048)
			(end -0.67945 0.3048)
			(stroke
				(width 0.1)
				(type default)
			)
			(layer "F.Fab")
		)
		(fp_line
			(start -0.67945 0.3048)
			(end -0.67945 -0.305054)
			(stroke
				(width 0.1)
				(type default)
			)
			(layer "F.Fab")
		)
		(pad "1" smd circle
			(at -0.40005 0 90)
			(size 0 0)
			(layers "F.Cu" "F.Mask" "F.Paste")
			(net "P5V_USB_REAR")
		)
		(pad "2" smd circle
			(at 0.40005 0 90)
			(size 0 0)
			(layers "F.Cu" "F.Mask" "F.Paste")
			(net "GND")
		)
	)
)
